(kicad_pcb
	(version 20260206)
	(generator "pcbnew")
	(generator_version "10.0")
	(general
		(thickness 1.6)
		(legacy_teardrops no)
	)
	(paper "A4")
	(title_block
		(title "fcb — 12433-1M.1206WZS1330.brd")
		(comment 1 "Open Vault / Knox (Wiwynn) / footprints 399-404 of 495")
	)
	(layers
		(0 "F.Cu" signal "TOP")
		(4 "In1.Cu" signal "L2GND")
		(6 "In2.Cu" signal "L3VCC")
		(2 "B.Cu" signal "BOTTOM")
		(9 "F.Adhes" user "F.Adhesive")
		(11 "B.Adhes" user "B.Adhesive")
		(13 "F.Paste" user "Package Geometry/Pastemask Top")
		(15 "B.Paste" user "Package Geometry/Pastemask Bottom")
		(5 "F.SilkS" user "Ref Des/Silkscreen Top")
		(7 "B.SilkS" user "Ref Des/Silkscreen Bottom")
		(1 "F.Mask" user "Board Geometry/Soldermask Top")
		(3 "B.Mask" user "Board Geometry/Soldermask Bottom")
		(17 "Dwgs.User" user "User.Drawings")
		(19 "Cmts.User" user "User.Comments")
		(21 "Eco1.User" user "User.Eco1")
		(23 "Eco2.User" user "User.Eco2")
		(25 "Edge.Cuts" user "Board Geometry/Outline")
		(27 "Margin" user)
		(31 "F.CrtYd" user "Package Geometry/Place Bound Top")
		(29 "B.CrtYd" user "Package Geometry/Place Bound Bottom")
		(35 "F.Fab" user "Ref Des/Assembly Top")
		(33 "B.Fab" user "Ref Des/Assembly Bottom")
	)
	(footprint ""
		(layer "F.Cu")
		(at 37.17671 -154.818334)
		(property "Reference" "C2"
			(at 0 0 0)
			(layer "F.SilkS")
			(hide yes)
			(effects
				(font
					(size 1.27 1.27)
				)
			)
		)
		(property "Value" "SCD1U16V2KX-3GP"
			(at 1.1811 -2.7051 0)
			(unlocked yes)
			(layer "F.Fab")
			(hide yes)
			(effects
				(font
					(size 1.016 1.016)
					(thickness 0.1524)
				)
			)
		)
		(property "Device Type" "C402H22"
			(at 1.1811 -4.2291 0)
			(unlocked yes)
			(layer "F.Fab")
			(hide yes)
			(effects
				(font
					(size 1.016 1.016)
					(thickness 0.1524)
				)
			)
		)
		(duplicate_pad_numbers_are_jumpers no)
		(fp_rect
			(start -0.4318 0.9525)
			(end 0.4318 -0.9525)
			(stroke
				(width 0)
				(type default)
			)
			(fill no)
			(layer "F.CrtYd")
		)
		(fp_rect
			(start -0.4318 0.9525)
			(end 0.4318 -0.9525)
			(stroke
				(width 0)
				(type default)
			)
			(fill no)
			(layer "F.Fab")
		)
		(pad "1" smd custom
			(at 0 -0.4445)
			(size 0.1524 0.1524)
			(layers "F.Cu" "F.Mask" "F.Paste")
			(net "NCT7904_3VDD")
			(options
				(clearance outline)
				(anchor circle)
			)
			(primitives
				(gr_poly
					(pts
						(arc
							(start 0.3048 -0.2032)
							(mid 0.275042 -0.275042)
							(end 0.2032 -0.3048)
						)
						(arc
							(start -0.2032 -0.3048)
							(mid -0.275042 -0.275042)
							(end -0.3048 -0.2032)
						)
						(arc
							(start -0.3048 0.2032)
							(mid -0.275042 0.275042)
							(end -0.2032 0.3048)
						)
						(arc
							(start 0.2032 0.3048)
							(mid 0.275042 0.275042)
							(end 0.3048 0.2032)
						)
					)
					(width 0)
					(fill yes)
				)
			)
		)
		(pad "2" smd custom
			(at 0 0.4445)
			(size 0.1524 0.1524)
			(layers "F.Cu" "F.Mask" "F.Paste")
			(net "GND")
			(options
				(clearance outline)
				(anchor circle)
			)
			(primitives
				(gr_poly
					(pts
						(arc
							(start 0.3048 -0.2032)
							(mid 0.275042 -0.275042)
							(end 0.2032 -0.3048)
						)
						(arc
							(start -0.2032 -0.3048)
							(mid -0.275042 -0.275042)
							(end -0.3048 -0.2032)
						)
						(arc
							(start -0.3048 0.2032)
							(mid -0.275042 0.275042)
							(end -0.2032 0.3048)
						)
						(arc
							(start 0.2032 0.3048)
							(mid 0.275042 0.275042)
							(end 0.3048 0.2032)
						)
					)
					(width 0)
					(fill yes)
				)
			)
		)
	)
	(footprint ""
		(layer "F.Cu")
		(at 34.925 -366.268)
		(property "Reference" "PR38"
			(at 0 0 0)
			(layer "F.SilkS")
			(hide yes)
			(effects
				(font
					(size 1.27 1.27)
				)
			)
		)
		(property "Value" "1KR2F-3-GP"
			(at 0.064008 -3.993896 0)
			(unlocked yes)
			(layer "F.Fab")
			(hide yes)
			(effects
				(font
					(size 1.016 1.016)
					(thickness 0.1524)
				)
			)
		)
		(property "Device Type" "R402H16"
			(at 0.064008 -5.517896 0)
			(unlocked yes)
			(layer "F.Fab")
			(hide yes)
			(effects
				(font
					(size 1.016 1.016)
					(thickness 0.1524)
				)
			)
		)
		(duplicate_pad_numbers_are_jumpers no)
		(fp_line
			(start -0.508 -0.9398)
			(end -0.508 0.9398)
			(stroke
				(width 0.1524)
				(type default)
			)
			(layer "F.SilkS")
		)
		(fp_line
			(start 0.508 -0.9398)
			(end -0.508 -0.9398)
			(stroke
				(width 0.1524)
				(type default)
			)
			(layer "F.SilkS")
		)
		(fp_rect
			(start -0.508 0.9398)
			(end 0.508 -0.9398)
			(stroke
				(width 0)
				(type default)
			)
			(fill no)
			(layer "F.CrtYd")
		)
		(fp_rect
			(start -0.508 0.9398)
			(end 0.508 -0.9398)
			(stroke
				(width 0)
				(type default)
			)
			(fill no)
			(layer "F.Fab")
		)
		(pad "1" smd custom
			(at 0 -0.4445)
			(size 0.1397 0.1397)
			(layers "F.Cu" "F.Mask" "F.Paste")
			(net "ADM1276_EN_NET")
			(options
				(clearance outline)
				(anchor circle)
			)
			(primitives
				(gr_poly
					(pts
						(arc
							(start -0.1778 -0.2794)
							(mid -0.249642 -0.249642)
							(end -0.2794 -0.1778)
						)
						(arc
							(start -0.2794 0.1778)
							(mid -0.249642 0.249642)
							(end -0.1778 0.2794)
						)
						(arc
							(start 0.1778 0.2794)
							(mid 0.249642 0.249642)
							(end 0.2794 0.1778)
						)
						(arc
							(start 0.2794 -0.1778)
							(mid 0.249642 -0.249642)
							(end 0.1778 -0.2794)
						)
					)
					(width 0)
					(fill yes)
				)
			)
		)
		(pad "2" smd custom
			(at 0 0.4445)
			(size 0.1397 0.1397)
			(layers "F.Cu" "F.Mask" "F.Paste")
			(net "ADM1276_EN")
			(options
				(clearance outline)
				(anchor circle)
			)
			(primitives
				(gr_poly
					(pts
						(arc
							(start -0.1778 -0.2794)
							(mid -0.249642 -0.249642)
							(end -0.2794 -0.1778)
						)
						(arc
							(start -0.2794 0.1778)
							(mid -0.249642 0.249642)
							(end -0.1778 0.2794)
						)
						(arc
							(start 0.1778 0.2794)
							(mid 0.249642 0.249642)
							(end 0.2794 0.1778)
						)
						(arc
							(start 0.2794 -0.1778)
							(mid 0.249642 -0.249642)
							(end 0.1778 -0.2794)
						)
					)
					(width 0)
					(fill yes)
				)
			)
		)
	)
	(footprint ""
		(layer "F.Cu")
		(at 7.949946 -232.134918 -90)
		(property "Reference" "LED4"
			(at 0 0 270)
			(layer "F.SilkS")
			(hide yes)
			(effects
				(font
					(size 1.27 1.27)
				)
			)
		)
		(property "Value" "LED-RB-6-GP"
			(at -4.6736 3.8354 270)
			(unlocked yes)
			(layer "F.Fab")
			(hide yes)
			(effects
				(font
					(size 1.016 1.016)
					(thickness 0.1524)
				)
			)
		)
		(property "Device Type" "LED-100-3P-067106H325"
			(at -4.6736 2.3114 270)
			(unlocked yes)
			(layer "F.Fab")
			(hide yes)
			(effects
				(font
					(size 1.016 1.016)
					(thickness 0.1524)
				)
			)
		)
		(duplicate_pad_numbers_are_jumpers no)
		(fp_line
			(start -1.7526 10.414)
			(end -1.7526 6.6548)
			(stroke
				(width 0.1524)
				(type default)
			)
			(layer "F.SilkS")
		)
		(fp_line
			(start 1.7526 10.414)
			(end -1.7526 10.414)
			(stroke
				(width 0.1524)
				(type default)
			)
			(layer "F.SilkS")
		)
		(fp_line
			(start -3.6068 6.6548)
			(end -3.6068 -0.889)
			(stroke
				(width 0.1524)
				(type default)
			)
			(layer "F.SilkS")
		)
		(fp_line
			(start -1.7526 6.6548)
			(end -3.6068 6.6548)
			(stroke
				(width 0.1524)
				(type default)
			)
			(layer "F.SilkS")
		)
		(fp_line
			(start 1.7526 6.6548)
			(end 1.7526 10.414)
			(stroke
				(width 0.1524)
				(type default)
			)
			(layer "F.SilkS")
		)
		(fp_line
			(start 3.6068 6.6548)
			(end 1.7526 6.6548)
			(stroke
				(width 0.1524)
				(type default)
			)
			(layer "F.SilkS")
		)
		(fp_line
			(start -3.6068 -0.889)
			(end 3.6068 -0.889)
			(stroke
				(width 0.1524)
				(type default)
			)
			(layer "F.SilkS")
		)
		(fp_line
			(start 3.6068 -0.889)
			(end 3.6068 6.6548)
			(stroke
				(width 0.1524)
				(type default)
			)
			(layer "F.SilkS")
		)
		(fp_circle
			(center -2.54 0)
			(end -2.54 -0.9906)
			(stroke
				(width 0.3048)
				(type default)
			)
			(fill no)
			(layer "F.SilkS")
		)
		(fp_circle
			(center 0 0)
			(end 0 -0.9906)
			(stroke
				(width 0.3048)
				(type default)
			)
			(fill no)
			(layer "F.SilkS")
		)
		(fp_circle
			(center 2.54 0)
			(end 2.54 -0.9906)
			(stroke
				(width 0.3048)
				(type default)
			)
			(fill no)
			(layer "F.SilkS")
		)
		(fp_poly
			(pts
				(xy -1.4986 10.1473) (xy -1.4986 6.4008) (xy -3.3528 6.4008) (xy -3.3528 -0.3937) (xy 3.3528 -0.3937)
				(xy 3.3528 6.4008) (xy 1.4986 6.4008) (xy 1.4986 10.1473)
			)
			(stroke
				(width 0)
				(type default)
			)
			(fill no)
			(layer "F.CrtYd")
		)
		(fp_poly
			(pts
				(xy -2.0066 10.668) (xy 2.0066 10.668) (xy 2.0066 6.9088) (xy 3.8608 6.9088) (xy 3.8608 2.2098)
				(xy 3.3528 2.2098) (xy 3.3528 6.4008) (xy 1.4986 6.4008) (xy 1.4986 10.1473) (xy -1.4986 10.1473)
				(xy -1.4986 6.4008) (xy -3.3528 6.4008) (xy -3.3528 -0.3937) (xy 3.3528 -0.3937) (xy 3.3528 2.1971)
				(xy 3.8608 2.1971) (xy 3.8608 -1.143) (xy -3.8608 -1.143) (xy -3.8608 6.9088) (xy -2.0066 6.9088)
			)
			(stroke
				(width 0)
				(type default)
			)
			(fill no)
			(layer "F.CrtYd")
		)
		(fp_poly
			(pts
				(xy -2.0066 10.668) (xy -2.0066 6.9088) (xy -3.8608 6.9088) (xy -3.8608 -1.143) (xy 3.8608 -1.143)
				(xy 3.8608 6.9088) (xy 2.0066 6.9088) (xy 2.0066 10.668)
			)
			(stroke
				(width 0)
				(type default)
			)
			(fill no)
			(layer "F.Fab")
		)
		(pad "1" thru_hole circle
			(at 2.54 0 270)
			(size 1.27 1.27)
			(drill 0.889)
			(layers "*.Cu" "*.Mask")
			(remove_unused_layers no)
			(net "LED_DR_LED3_BLUE")
			(clearance 0.1651)
			(thermal_gap 0.1651)
		)
		(pad "2" thru_hole circle
			(at 0 0 270)
			(size 1.27 1.27)
			(drill 0.889)
			(layers "*.Cu" "*.Mask")
			(remove_unused_layers no)
			(net "LED_DR_LED3_K")
			(clearance 0.1651)
			(thermal_gap 0.1651)
		)
		(pad "3" thru_hole circle
			(at -2.54 0 270)
			(size 1.27 1.27)
			(drill 0.889)
			(layers "*.Cu" "*.Mask")
			(remove_unused_layers no)
			(net "LED_DR_LED3")
			(clearance 0.1651)
			(thermal_gap 0.1651)
		)
	)
	(footprint ""
		(layer "F.Cu")
		(at 14.8082 -66.4464 180)
		(property "Reference" "R150"
			(at 0 0 180)
			(layer "F.SilkS")
			(hide yes)
			(effects
				(font
					(size 1.27 1.27)
				)
			)
		)
		(property "Value" "10R2F-L-GP"
			(at 0.064008 -3.993896 180)
			(unlocked yes)
			(layer "F.Fab")
			(hide yes)
			(effects
				(font
					(size 1.016 1.016)
					(thickness 0.1524)
				)
			)
		)
		(property "Device Type" "R402H14"
			(at 0.064008 -5.517896 180)
			(unlocked yes)
			(layer "F.Fab")
			(hide yes)
			(effects
				(font
					(size 1.016 1.016)
					(thickness 0.1524)
				)
			)
		)
		(duplicate_pad_numbers_are_jumpers no)
		(fp_line
			(start 0.508 -0.9398)
			(end -0.508 -0.9398)
			(stroke
				(width 0.1524)
				(type default)
			)
			(layer "F.SilkS")
		)
		(fp_line
			(start -0.508 -0.9398)
			(end -0.508 0.9398)
			(stroke
				(width 0.1524)
				(type default)
			)
			(layer "F.SilkS")
		)
		(fp_rect
			(start -0.508 0.9398)
			(end 0.508 -0.9398)
			(stroke
				(width 0)
				(type default)
			)
			(fill no)
			(layer "F.CrtYd")
		)
		(fp_rect
			(start -0.508 0.9398)
			(end 0.508 -0.9398)
			(stroke
				(width 0)
				(type default)
			)
			(fill no)
			(layer "F.Fab")
		)
		(pad "1" smd custom
			(at 0 -0.4445 180)
			(size 0.1397 0.1397)
			(layers "F.Cu" "F.Mask" "F.Paste")
			(net "I2C_C_SDA_CONN_R")
			(options
				(clearance outline)
				(anchor circle)
			)
			(primitives
				(gr_poly
					(pts
						(arc
							(start -0.1778 -0.2794)
							(mid -0.249642 -0.249642)
							(end -0.2794 -0.1778)
						)
						(arc
							(start -0.2794 0.1778)
							(mid -0.249642 0.249642)
							(end -0.1778 0.2794)
						)
						(arc
							(start 0.1778 0.2794)
							(mid 0.249642 0.249642)
							(end 0.2794 0.1778)
						)
						(arc
							(start 0.2794 -0.1778)
							(mid 0.249642 -0.249642)
							(end 0.1778 -0.2794)
						)
					)
					(width 0)
					(fill yes)
				)
			)
		)
		(pad "2" smd custom
			(at 0 0.4445 180)
			(size 0.1397 0.1397)
			(layers "F.Cu" "F.Mask" "F.Paste")
			(net "I2C_C_SDA")
			(options
				(clearance outline)
				(anchor circle)
			)
			(primitives
				(gr_poly
					(pts
						(arc
							(start -0.1778 -0.2794)
							(mid -0.249642 -0.249642)
							(end -0.2794 -0.1778)
						)
						(arc
							(start -0.2794 0.1778)
							(mid -0.249642 0.249642)
							(end -0.1778 0.2794)
						)
						(arc
							(start 0.1778 0.2794)
							(mid 0.249642 0.249642)
							(end 0.2794 0.1778)
						)
						(arc
							(start 0.2794 -0.1778)
							(mid 0.249642 -0.249642)
							(end 0.1778 -0.2794)
						)
					)
					(width 0)
					(fill yes)
				)
			)
		)
	)
	(footprint ""
		(layer "F.Cu")
		(at 41.529 -252.984)
		(property "Reference" "R149"
			(at 0 0 0)
			(layer "F.SilkS")
			(hide yes)
			(effects
				(font
					(size 1.27 1.27)
				)
			)
		)
		(property "Value" "330R2J-3-GP"
			(at 0.064008 -3.993896 0)
			(unlocked yes)
			(layer "F.Fab")
			(hide yes)
			(effects
				(font
					(size 1.016 1.016)
					(thickness 0.1524)
				)
			)
		)
		(property "Device Type" "R402H16"
			(at 0.064008 -5.517896 0)
			(unlocked yes)
			(layer "F.Fab")
			(hide yes)
			(effects
				(font
					(size 1.016 1.016)
					(thickness 0.1524)
				)
			)
		)
		(duplicate_pad_numbers_are_jumpers no)
		(fp_line
			(start -0.508 -0.9398)
			(end -0.508 0.9398)
			(stroke
				(width 0.1524)
				(type default)
			)
			(layer "F.SilkS")
		)
		(fp_line
			(start 0.508 -0.9398)
			(end -0.508 -0.9398)
			(stroke
				(width 0.1524)
				(type default)
			)
			(layer "F.SilkS")
		)
		(fp_rect
			(start -0.508 0.9398)
			(end 0.508 -0.9398)
			(stroke
				(width 0)
				(type default)
			)
			(fill no)
			(layer "F.CrtYd")
		)
		(fp_rect
			(start -0.508 0.9398)
			(end 0.508 -0.9398)
			(stroke
				(width 0)
				(type default)
			)
			(fill no)
			(layer "F.Fab")
		)
		(pad "1" smd custom
			(at 0 -0.4445)
			(size 0.1397 0.1397)
			(layers "F.Cu" "F.Mask" "F.Paste")
			(net "P3V3")
			(options
				(clearance outline)
				(anchor circle)
			)
			(primitives
				(gr_poly
					(pts
						(arc
							(start -0.1778 -0.2794)
							(mid -0.249642 -0.249642)
							(end -0.2794 -0.1778)
						)
						(arc
							(start -0.2794 0.1778)
							(mid -0.249642 0.249642)
							(end -0.1778 0.2794)
						)
						(arc
							(start 0.1778 0.2794)
							(mid 0.249642 0.249642)
							(end 0.2794 0.1778)
						)
						(arc
							(start 0.2794 -0.1778)
							(mid 0.249642 -0.249642)
							(end 0.1778 -0.2794)
						)
					)
					(width 0)
					(fill yes)
				)
			)
		)
		(pad "2" smd custom
			(at 0 0.4445)
			(size 0.1397 0.1397)
			(layers "F.Cu" "F.Mask" "F.Paste")
			(net "LED_DR_LED4")
			(options
				(clearance outline)
				(anchor circle)
			)
			(primitives
				(gr_poly
					(pts
						(arc
							(start -0.1778 -0.2794)
							(mid -0.249642 -0.249642)
							(end -0.2794 -0.1778)
						)
						(arc
							(start -0.2794 0.1778)
							(mid -0.249642 0.249642)
							(end -0.1778 0.2794)
						)
						(arc
							(start 0.1778 0.2794)
							(mid 0.249642 0.249642)
							(end 0.2794 0.1778)
						)
						(arc
							(start 0.2794 -0.1778)
							(mid 0.249642 -0.249642)
							(end 0.1778 -0.2794)
						)
					)
					(width 0)
					(fill yes)
				)
			)
		)
	)
	(footprint ""
		(layer "F.Cu")
		(at 20.675092 -288.278062 180)
		(property "Reference" "R99"
			(at 0 0 180)
			(layer "F.SilkS")
			(hide yes)
			(effects
				(font
					(size 1.27 1.27)
				)
			)
		)
		(property "Value" "27KR3F-GP"
			(at -0.0254 -2.5146 180)
			(unlocked yes)
			(layer "F.Fab")
			(hide yes)
			(effects
				(font
					(size 1.016 1.016)
					(thickness 0.1524)
				)
			)
		)
		(property "Device Type" "R603H22"
			(at -0.0254 -4.0386 180)
			(unlocked yes)
			(layer "F.Fab")
			(hide yes)
			(effects
				(font
					(size 1.016 1.016)
					(thickness 0.1524)
				)
			)
		)
		(duplicate_pad_numbers_are_jumpers no)
		(fp_line
			(start 0.2032 0)
			(end 0.4826 0)
			(stroke
				(width 0.2032)
				(type default)
			)
			(layer "F.SilkS")
		)
		(fp_line
			(start -0.4826 0)
			(end -0.2032 0)
			(stroke
				(width 0.2032)
				(type default)
			)
			(layer "F.SilkS")
		)
		(fp_rect
			(start -0.5842 1.3335)
			(end 0.5842 -1.3335)
			(stroke
				(width 0)
				(type default)
			)
			(fill no)
			(layer "F.CrtYd")
		)
		(fp_rect
			(start -0.5842 1.3335)
			(end 0.5842 -1.3335)
			(stroke
				(width 0)
				(type default)
			)
			(fill no)
			(layer "F.Fab")
		)
		(pad "1" smd custom
			(at 0 -0.762 180)
			(size 0.2159 0.2159)
			(layers "F.Cu" "F.Mask" "F.Paste")
			(net "FAN_TACH4")
			(options
				(clearance outline)
				(anchor circle)
			)
			(primitives
				(gr_poly
					(pts
						(arc
							(start -0.3302 -0.4318)
							(mid -0.402042 -0.402042)
							(end -0.4318 -0.3302)
						)
						(arc
							(start -0.4318 0.3302)
							(mid -0.402042 0.402042)
							(end -0.3302 0.4318)
						)
						(arc
							(start 0.3302 0.4318)
							(mid 0.402042 0.402042)
							(end 0.4318 0.3302)
						)
						(arc
							(start 0.4318 -0.3302)
							(mid 0.402042 -0.402042)
							(end 0.3302 -0.4318)
						)
					)
					(width 0)
					(fill yes)
				)
			)
		)
		(pad "2" smd custom
			(at 0 0.762 180)
			(size 0.2159 0.2159)
			(layers "F.Cu" "F.Mask" "F.Paste")
			(net "FANIN_4")
			(options
				(clearance outline)
				(anchor circle)
			)
			(primitives
				(gr_poly
					(pts
						(arc
							(start -0.3302 -0.4318)
							(mid -0.402042 -0.402042)
							(end -0.4318 -0.3302)
						)
						(arc
							(start -0.4318 0.3302)
							(mid -0.402042 0.402042)
							(end -0.3302 0.4318)
						)
						(arc
							(start 0.3302 0.4318)
							(mid 0.402042 0.402042)
							(end 0.4318 0.3302)
						)
						(arc
							(start 0.4318 -0.3302)
							(mid 0.402042 -0.402042)
							(end 0.3302 -0.4318)
						)
					)
					(width 0)
					(fill yes)
				)
			)
		)
	)
)
